(kicad_pcb
	(version 20260206)
	(generator "pcbnew")
	(generator_version "10.0")
	(general
		(thickness 1.6)
		(legacy_teardrops no)
	)
	(paper "A4")
	(title_block
		(title "03242023_DA0F0TMBIJ0_F0T_Motherboard_J_brd_V01_OCP.brd")
		(comment 1 "Grand Teton / footprints 3446-3452 of 6105")
	)
	(layers
		(0 "F.Cu" signal "TOP")
		(4 "In1.Cu" signal "GND")
		(6 "In2.Cu" signal "IN1")
		(8 "In3.Cu" signal "GND1")
		(10 "In4.Cu" signal "IN2")
		(12 "In5.Cu" signal "GND2")
		(14 "In6.Cu" signal "IN3")
		(16 "In7.Cu" signal "GND3")
		(18 "In8.Cu" signal "VCC")
		(20 "In9.Cu" signal "VCC1")
		(22 "In10.Cu" signal "GND4")
		(24 "In11.Cu" signal "IN4")
		(26 "In12.Cu" signal "GND5")
		(28 "In13.Cu" signal "IN5")
		(30 "In14.Cu" signal "GND6")
		(32 "In15.Cu" signal "IN6")
		(34 "In16.Cu" signal "GND7")
		(2 "B.Cu" signal "BOTTOM")
		(9 "F.Adhes" user "F.Adhesive")
		(11 "B.Adhes" user "B.Adhesive")
		(13 "F.Paste" user "Package Geometry/Pastemask Top")
		(15 "B.Paste" user "Package Geometry/Pastemask Bottom")
		(5 "F.SilkS" user "Ref Des/Silkscreen Top")
		(7 "B.SilkS" user "Ref Des/Silkscreen Bottom")
		(1 "F.Mask" user "Board Geometry/Soldermask Top")
		(3 "B.Mask" user "Board Geometry/Soldermask Bottom")
		(17 "Dwgs.User" user "User.Drawings")
		(19 "Cmts.User" user "User.Comments")
		(21 "Eco1.User" user "User.Eco1")
		(23 "Eco2.User" user "User.Eco2")
		(25 "Edge.Cuts" user "Board Geometry/Outline")
		(27 "Margin" user)
		(31 "F.CrtYd" user "Package Geometry/Place Bound Top")
		(29 "B.CrtYd" user "Package Geometry/Place Bound Bottom")
		(35 "F.Fab" user "Ref Des/Assembly Top")
		(33 "B.Fab" user "Ref Des/Assembly Bottom")
	)
	(footprint ""
		(layer "F.Cu")
		(at 38.774878 -16.099536 90)
		(property "Reference" "C822"
			(at 0 0 90)
			(layer "F.SilkS")
			(hide yes)
			(effects
				(font
					(size 1.27 1.27)
				)
			)
		)
		(property "Value" ""
			(at 0 0 90)
			(layer "F.Fab")
			(effects
				(font
					(size 1.27 1.27)
				)
			)
		)
		(duplicate_pad_numbers_are_jumpers no)
		(fp_line
			(start 0.299974 -0.150114)
			(end 0.299974 0.150114)
			(stroke
				(width 0.1)
				(type default)
			)
			(layer "F.Fab")
		)
		(fp_line
			(start -0.299974 -0.150114)
			(end 0.299974 -0.150114)
			(stroke
				(width 0.1)
				(type default)
			)
			(layer "F.Fab")
		)
		(fp_line
			(start 0.299974 0.150114)
			(end -0.299974 0.150114)
			(stroke
				(width 0.1)
				(type default)
			)
			(layer "F.Fab")
		)
		(fp_line
			(start -0.299974 0.150114)
			(end -0.299974 -0.150114)
			(stroke
				(width 0.1)
				(type default)
			)
			(layer "F.Fab")
		)
		(pad "1" smd rect
			(at -0.2667 0 90)
			(size 0.3048 0.381)
			(layers "F.Cu" "F.Mask" "F.Paste")
			(net "P5E_CPU1_PE1_TX_C_DN<7>")
		)
		(pad "2" smd rect
			(at 0.2667 0 90)
			(size 0.3048 0.381)
			(layers "F.Cu" "F.Mask" "F.Paste")
			(net "P5E_CPU1_PE1_TX_DN<7>")
		)
	)
	(footprint ""
		(layer "F.Cu")
		(at 165.15715 -431.087276 -90)
		(property "Reference" "R2707"
			(at 0 0 270)
			(layer "F.SilkS")
			(hide yes)
			(effects
				(font
					(size 1.27 1.27)
				)
			)
		)
		(property "Value" ""
			(at 0 0 270)
			(layer "F.Fab")
			(effects
				(font
					(size 1.27 1.27)
				)
			)
		)
		(duplicate_pad_numbers_are_jumpers no)
		(fp_line
			(start -0.7874 0.4064)
			(end -0.7874 -0.4064)
			(stroke
				(width 0.1524)
				(type default)
			)
			(layer "F.SilkS")
		)
		(fp_line
			(start 0.7874 0.4064)
			(end -0.7874 0.4064)
			(stroke
				(width 0.1524)
				(type default)
			)
			(layer "F.SilkS")
		)
		(fp_line
			(start -0.7874 -0.4064)
			(end 0.7874 -0.4064)
			(stroke
				(width 0.1524)
				(type default)
			)
			(layer "F.SilkS")
		)
		(fp_line
			(start 0.7874 -0.4064)
			(end 0.7874 0.4064)
			(stroke
				(width 0.1524)
				(type default)
			)
			(layer "F.SilkS")
		)
		(fp_line
			(start -0.67945 0.3048)
			(end -0.67945 -0.305054)
			(stroke
				(width 0.1)
				(type default)
			)
			(layer "F.Fab")
		)
		(fp_line
			(start -0.12065 0.3048)
			(end -0.67945 0.3048)
			(stroke
				(width 0.1)
				(type default)
			)
			(layer "F.Fab")
		)
		(fp_line
			(start 0.120396 0.3048)
			(end 0.120396 0.2794)
			(stroke
				(width 0.1)
				(type default)
			)
			(layer "F.Fab")
		)
		(fp_line
			(start 0.67945 0.3048)
			(end 0.120396 0.3048)
			(stroke
				(width 0.1)
				(type default)
			)
			(layer "F.Fab")
		)
		(fp_line
			(start -0.12065 0.2794)
			(end -0.12065 0.3048)
			(stroke
				(width 0.1)
				(type default)
			)
			(layer "F.Fab")
		)
		(fp_line
			(start 0.120396 0.2794)
			(end -0.12065 0.2794)
			(stroke
				(width 0.1)
				(type default)
			)
			(layer "F.Fab")
		)
		(fp_line
			(start -0.12065 -0.2794)
			(end 0.12065 -0.2794)
			(stroke
				(width 0.1)
				(type default)
			)
			(layer "F.Fab")
		)
		(fp_line
			(start 0.12065 -0.2794)
			(end 0.12065 -0.3048)
			(stroke
				(width 0.1)
				(type default)
			)
			(layer "F.Fab")
		)
		(fp_line
			(start 0.12065 -0.3048)
			(end 0.67945 -0.3048)
			(stroke
				(width 0.1)
				(type default)
			)
			(layer "F.Fab")
		)
		(fp_line
			(start 0.67945 -0.3048)
			(end 0.67945 0.3048)
			(stroke
				(width 0.1)
				(type default)
			)
			(layer "F.Fab")
		)
		(fp_line
			(start -0.67945 -0.305054)
			(end -0.12065 -0.305054)
			(stroke
				(width 0.1)
				(type default)
			)
			(layer "F.Fab")
		)
		(fp_line
			(start -0.12065 -0.305054)
			(end -0.12065 -0.2794)
			(stroke
				(width 0.1)
				(type default)
			)
			(layer "F.Fab")
		)
		(pad "1" smd circle
			(at -0.40005 0 270)
			(size 0 0)
			(layers "F.Cu" "F.Mask" "F.Paste")
			(net "SMB_BMC_SWB_EN")
		)
		(pad "2" smd circle
			(at 0.40005 0 270)
			(size 0 0)
			(layers "F.Cu" "F.Mask" "F.Paste")
			(net "SMB_BMC_SWB_EN_R")
		)
	)
	(footprint ""
		(layer "F.Cu")
		(at 105.315004 -245.634256 -90)
		(property "Reference" "C237"
			(at 0 0 270)
			(layer "F.SilkS")
			(hide yes)
			(effects
				(font
					(size 1.27 1.27)
				)
			)
		)
		(property "Value" ""
			(at 0 0 270)
			(layer "F.Fab")
			(effects
				(font
					(size 1.27 1.27)
				)
			)
		)
		(duplicate_pad_numbers_are_jumpers no)
		(fp_line
			(start -0.7874 0.4064)
			(end -0.7874 -0.4064)
			(stroke
				(width 0.1524)
				(type default)
			)
			(layer "F.SilkS")
		)
		(fp_line
			(start 0.7874 0.4064)
			(end -0.7874 0.4064)
			(stroke
				(width 0.1524)
				(type default)
			)
			(layer "F.SilkS")
		)
		(fp_line
			(start -0.7874 -0.4064)
			(end 0.7874 -0.4064)
			(stroke
				(width 0.1524)
				(type default)
			)
			(layer "F.SilkS")
		)
		(fp_line
			(start 0.7874 -0.4064)
			(end 0.7874 0.4064)
			(stroke
				(width 0.1524)
				(type default)
			)
			(layer "F.SilkS")
		)
		(fp_line
			(start -0.67945 0.3048)
			(end -0.67945 -0.305054)
			(stroke
				(width 0.1)
				(type default)
			)
			(layer "F.Fab")
		)
		(fp_line
			(start -0.12065 0.3048)
			(end -0.67945 0.3048)
			(stroke
				(width 0.1)
				(type default)
			)
			(layer "F.Fab")
		)
		(fp_line
			(start 0.120396 0.3048)
			(end 0.120396 0.2794)
			(stroke
				(width 0.1)
				(type default)
			)
			(layer "F.Fab")
		)
		(fp_line
			(start 0.67945 0.3048)
			(end 0.120396 0.3048)
			(stroke
				(width 0.1)
				(type default)
			)
			(layer "F.Fab")
		)
		(fp_line
			(start -0.12065 0.2794)
			(end -0.12065 0.3048)
			(stroke
				(width 0.1)
				(type default)
			)
			(layer "F.Fab")
		)
		(fp_line
			(start 0.120396 0.2794)
			(end -0.12065 0.2794)
			(stroke
				(width 0.1)
				(type default)
			)
			(layer "F.Fab")
		)
		(fp_line
			(start -0.12065 -0.2794)
			(end 0.12065 -0.2794)
			(stroke
				(width 0.1)
				(type default)
			)
			(layer "F.Fab")
		)
		(fp_line
			(start 0.12065 -0.2794)
			(end 0.12065 -0.3048)
			(stroke
				(width 0.1)
				(type default)
			)
			(layer "F.Fab")
		)
		(fp_line
			(start 0.12065 -0.3048)
			(end 0.67945 -0.3048)
			(stroke
				(width 0.1)
				(type default)
			)
			(layer "F.Fab")
		)
		(fp_line
			(start 0.67945 -0.3048)
			(end 0.67945 0.3048)
			(stroke
				(width 0.1)
				(type default)
			)
			(layer "F.Fab")
		)
		(fp_line
			(start -0.67945 -0.305054)
			(end -0.12065 -0.305054)
			(stroke
				(width 0.1)
				(type default)
			)
			(layer "F.Fab")
		)
		(fp_line
			(start -0.12065 -0.305054)
			(end -0.12065 -0.2794)
			(stroke
				(width 0.1)
				(type default)
			)
			(layer "F.Fab")
		)
		(pad "1" smd circle
			(at -0.40005 0 270)
			(size 0 0)
			(layers "F.Cu" "F.Mask" "F.Paste")
			(net "PVCCIN_CPU1")
		)
		(pad "2" smd circle
			(at 0.40005 0 270)
			(size 0 0)
			(layers "F.Cu" "F.Mask" "F.Paste")
			(net "GND")
		)
	)
	(footprint ""
		(layer "F.Cu")
		(at 117.22608 -119.846598 -90)
		(property "Reference" "R854"
			(at 0 0 270)
			(layer "F.SilkS")
			(hide yes)
			(effects
				(font
					(size 1.27 1.27)
				)
			)
		)
		(property "Value" ""
			(at 0 0 270)
			(layer "F.Fab")
			(effects
				(font
					(size 1.27 1.27)
				)
			)
		)
		(duplicate_pad_numbers_are_jumpers no)
		(fp_line
			(start -0.7874 0.4064)
			(end -0.7874 -0.4064)
			(stroke
				(width 0.1524)
				(type default)
			)
			(layer "F.SilkS")
		)
		(fp_line
			(start 0.7874 0.4064)
			(end -0.7874 0.4064)
			(stroke
				(width 0.1524)
				(type default)
			)
			(layer "F.SilkS")
		)
		(fp_line
			(start -0.7874 -0.4064)
			(end 0.7874 -0.4064)
			(stroke
				(width 0.1524)
				(type default)
			)
			(layer "F.SilkS")
		)
		(fp_line
			(start 0.7874 -0.4064)
			(end 0.7874 0.4064)
			(stroke
				(width 0.1524)
				(type default)
			)
			(layer "F.SilkS")
		)
		(fp_line
			(start -0.67945 0.3048)
			(end -0.67945 -0.305054)
			(stroke
				(width 0.1)
				(type default)
			)
			(layer "F.Fab")
		)
		(fp_line
			(start -0.12065 0.3048)
			(end -0.67945 0.3048)
			(stroke
				(width 0.1)
				(type default)
			)
			(layer "F.Fab")
		)
		(fp_line
			(start 0.120396 0.3048)
			(end 0.120396 0.2794)
			(stroke
				(width 0.1)
				(type default)
			)
			(layer "F.Fab")
		)
		(fp_line
			(start 0.67945 0.3048)
			(end 0.120396 0.3048)
			(stroke
				(width 0.1)
				(type default)
			)
			(layer "F.Fab")
		)
		(fp_line
			(start -0.12065 0.2794)
			(end -0.12065 0.3048)
			(stroke
				(width 0.1)
				(type default)
			)
			(layer "F.Fab")
		)
		(fp_line
			(start 0.120396 0.2794)
			(end -0.12065 0.2794)
			(stroke
				(width 0.1)
				(type default)
			)
			(layer "F.Fab")
		)
		(fp_line
			(start -0.12065 -0.2794)
			(end 0.12065 -0.2794)
			(stroke
				(width 0.1)
				(type default)
			)
			(layer "F.Fab")
		)
		(fp_line
			(start 0.12065 -0.2794)
			(end 0.12065 -0.3048)
			(stroke
				(width 0.1)
				(type default)
			)
			(layer "F.Fab")
		)
		(fp_line
			(start 0.12065 -0.3048)
			(end 0.67945 -0.3048)
			(stroke
				(width 0.1)
				(type default)
			)
			(layer "F.Fab")
		)
		(fp_line
			(start 0.67945 -0.3048)
			(end 0.67945 0.3048)
			(stroke
				(width 0.1)
				(type default)
			)
			(layer "F.Fab")
		)
		(fp_line
			(start -0.67945 -0.305054)
			(end -0.12065 -0.305054)
			(stroke
				(width 0.1)
				(type default)
			)
			(layer "F.Fab")
		)
		(fp_line
			(start -0.12065 -0.305054)
			(end -0.12065 -0.2794)
			(stroke
				(width 0.1)
				(type default)
			)
			(layer "F.Fab")
		)
		(pad "1" smd circle
			(at -0.40005 0 270)
			(size 0 0)
			(layers "F.Cu" "F.Mask" "F.Paste")
			(net "RST_CPU0_DRAM_GH_N")
		)
		(pad "2" smd circle
			(at 0.40005 0 270)
			(size 0 0)
			(layers "F.Cu" "F.Mask" "F.Paste")
			(net "RST_CPU0_DRAM_GH_PLD_N")
		)
	)
	(footprint ""
		(layer "F.Cu")
		(at 431.33518 -58.034428 90)
		(property "Reference" "C1340"
			(at 0 0 90)
			(layer "F.SilkS")
			(hide yes)
			(effects
				(font
					(size 1.27 1.27)
				)
			)
		)
		(property "Value" ""
			(at 0 0 90)
			(layer "F.Fab")
			(effects
				(font
					(size 1.27 1.27)
				)
			)
		)
		(duplicate_pad_numbers_are_jumpers no)
		(fp_line
			(start 1.524 -0.762)
			(end 1.524 0.762)
			(stroke
				(width 0.1524)
				(type default)
			)
			(layer "F.SilkS")
		)
		(fp_line
			(start -1.524 -0.762)
			(end 1.524 -0.762)
			(stroke
				(width 0.1524)
				(type default)
			)
			(layer "F.SilkS")
		)
		(fp_line
			(start 1.524 0.762)
			(end -1.524 0.762)
			(stroke
				(width 0.1524)
				(type default)
			)
			(layer "F.SilkS")
		)
		(fp_line
			(start -1.524 0.762)
			(end -1.524 -0.762)
			(stroke
				(width 0.1524)
				(type default)
			)
			(layer "F.SilkS")
		)
		(fp_line
			(start 1.1049 -0.724916)
			(end -1.1049 -0.724916)
			(stroke
				(width 0.1)
				(type default)
			)
			(layer "F.Fab")
		)
		(fp_line
			(start -1.1049 -0.724916)
			(end -1.1049 0.724916)
			(stroke
				(width 0.1)
				(type default)
			)
			(layer "F.Fab")
		)
		(fp_line
			(start 1.1049 0.724916)
			(end 1.1049 -0.724916)
			(stroke
				(width 0.1)
				(type default)
			)
			(layer "F.Fab")
		)
		(fp_line
			(start -1.1049 0.724916)
			(end 1.1049 0.724916)
			(stroke
				(width 0.1)
				(type default)
			)
			(layer "F.Fab")
		)
		(pad "1" smd rect
			(at -0.889 0 270)
			(size 1.016 1.27)
			(layers "F.Cu" "F.Mask" "F.Paste")
			(net "P3V3")
		)
		(pad "2" smd rect
			(at 0.889 0 270)
			(size 1.016 1.27)
			(layers "F.Cu" "F.Mask" "F.Paste")
			(net "GND")
		)
	)
	(footprint ""
		(layer "F.Cu")
		(at 179.352448 -401.239482 180)
		(property "Reference" "PC2103"
			(at 0 0 180)
			(layer "F.SilkS")
			(hide yes)
			(effects
				(font
					(size 1.27 1.27)
				)
			)
		)
		(property "Value" ""
			(at 0 0 180)
			(layer "F.Fab")
			(effects
				(font
					(size 1.27 1.27)
				)
			)
		)
		(duplicate_pad_numbers_are_jumpers no)
		(fp_line
			(start 0.7874 0.4064)
			(end -0.7874 0.4064)
			(stroke
				(width 0.1524)
				(type default)
			)
			(layer "F.SilkS")
		)
		(fp_line
			(start 0.7874 -0.4064)
			(end 0.7874 0.4064)
			(stroke
				(width 0.1524)
				(type default)
			)
			(layer "F.SilkS")
		)
		(fp_line
			(start -0.7874 0.4064)
			(end -0.7874 -0.4064)
			(stroke
				(width 0.1524)
				(type default)
			)
			(layer "F.SilkS")
		)
		(fp_line
			(start -0.7874 -0.4064)
			(end 0.7874 -0.4064)
			(stroke
				(width 0.1524)
				(type default)
			)
			(layer "F.SilkS")
		)
		(fp_line
			(start 0.67945 0.3048)
			(end 0.120396 0.3048)
			(stroke
				(width 0.1)
				(type default)
			)
			(layer "F.Fab")
		)
		(fp_line
			(start 0.67945 -0.3048)
			(end 0.67945 0.3048)
			(stroke
				(width 0.1)
				(type default)
			)
			(layer "F.Fab")
		)
		(fp_line
			(start 0.12065 -0.2794)
			(end 0.12065 -0.3048)
			(stroke
				(width 0.1)
				(type default)
			)
			(layer "F.Fab")
		)
		(fp_line
			(start 0.12065 -0.3048)
			(end 0.67945 -0.3048)
			(stroke
				(width 0.1)
				(type default)
			)
			(layer "F.Fab")
		)
		(fp_line
			(start 0.120396 0.3048)
			(end 0.120396 0.2794)
			(stroke
				(width 0.1)
				(type default)
			)
			(layer "F.Fab")
		)
		(fp_line
			(start 0.120396 0.2794)
			(end -0.12065 0.2794)
			(stroke
				(width 0.1)
				(type default)
			)
			(layer "F.Fab")
		)
		(fp_line
			(start -0.12065 0.3048)
			(end -0.67945 0.3048)
			(stroke
				(width 0.1)
				(type default)
			)
			(layer "F.Fab")
		)
		(fp_line
			(start -0.12065 0.2794)
			(end -0.12065 0.3048)
			(stroke
				(width 0.1)
				(type default)
			)
			(layer "F.Fab")
		)
		(fp_line
			(start -0.12065 -0.2794)
			(end 0.12065 -0.2794)
			(stroke
				(width 0.1)
				(type default)
			)
			(layer "F.Fab")
		)
		(fp_line
			(start -0.12065 -0.305054)
			(end -0.12065 -0.2794)
			(stroke
				(width 0.1)
				(type default)
			)
			(layer "F.Fab")
		)
		(fp_line
			(start -0.67945 0.3048)
			(end -0.67945 -0.305054)
			(stroke
				(width 0.1)
				(type default)
			)
			(layer "F.Fab")
		)
		(fp_line
			(start -0.67945 -0.305054)
			(end -0.12065 -0.305054)
			(stroke
				(width 0.1)
				(type default)
			)
			(layer "F.Fab")
		)
		(pad "1" smd circle
			(at -0.40005 0 180)
			(size 0 0)
			(layers "F.Cu" "F.Mask" "F.Paste")
			(net "HSC_VDD18")
		)
		(pad "2" smd circle
			(at 0.40005 0 180)
			(size 0 0)
			(layers "F.Cu" "F.Mask" "F.Paste")
			(net "AGND_HSC")
		)
	)
	(footprint ""
		(layer "F.Cu")
		(at 354.8126 -408.818588 180)
		(property "Reference" "R4558"
			(at 0 0 180)
			(layer "F.SilkS")
			(hide yes)
			(effects
				(font
					(size 1.27 1.27)
				)
			)
		)
		(property "Value" ""
			(at 0 0 180)
			(layer "F.Fab")
			(effects
				(font
					(size 1.27 1.27)
				)
			)
		)
		(duplicate_pad_numbers_are_jumpers no)
		(fp_line
			(start 0.7874 0.4064)
			(end -0.7874 0.4064)
			(stroke
				(width 0.1524)
				(type default)
			)
			(layer "F.SilkS")
		)
		(fp_line
			(start 0.7874 -0.4064)
			(end 0.7874 0.4064)
			(stroke
				(width 0.1524)
				(type default)
			)
			(layer "F.SilkS")
		)
		(fp_line
			(start -0.7874 0.4064)
			(end -0.7874 -0.4064)
			(stroke
				(width 0.1524)
				(type default)
			)
			(layer "F.SilkS")
		)
		(fp_line
			(start -0.7874 -0.4064)
			(end 0.7874 -0.4064)
			(stroke
				(width 0.1524)
				(type default)
			)
			(layer "F.SilkS")
		)
		(fp_line
			(start 0.67945 0.3048)
			(end 0.120396 0.3048)
			(stroke
				(width 0.1)
				(type default)
			)
			(layer "F.Fab")
		)
		(fp_line
			(start 0.67945 -0.3048)
			(end 0.67945 0.3048)
			(stroke
				(width 0.1)
				(type default)
			)
			(layer "F.Fab")
		)
		(fp_line
			(start 0.12065 -0.2794)
			(end 0.12065 -0.3048)
			(stroke
				(width 0.1)
				(type default)
			)
			(layer "F.Fab")
		)
		(fp_line
			(start 0.12065 -0.3048)
			(end 0.67945 -0.3048)
			(stroke
				(width 0.1)
				(type default)
			)
			(layer "F.Fab")
		)
		(fp_line
			(start 0.120396 0.3048)
			(end 0.120396 0.2794)
			(stroke
				(width 0.1)
				(type default)
			)
			(layer "F.Fab")
		)
		(fp_line
			(start 0.120396 0.2794)
			(end -0.12065 0.2794)
			(stroke
				(width 0.1)
				(type default)
			)
			(layer "F.Fab")
		)
		(fp_line
			(start -0.12065 0.3048)
			(end -0.67945 0.3048)
			(stroke
				(width 0.1)
				(type default)
			)
			(layer "F.Fab")
		)
		(fp_line
			(start -0.12065 0.2794)
			(end -0.12065 0.3048)
			(stroke
				(width 0.1)
				(type default)
			)
			(layer "F.Fab")
		)
		(fp_line
			(start -0.12065 -0.2794)
			(end 0.12065 -0.2794)
			(stroke
				(width 0.1)
				(type default)
			)
			(layer "F.Fab")
		)
		(fp_line
			(start -0.12065 -0.305054)
			(end -0.12065 -0.2794)
			(stroke
				(width 0.1)
				(type default)
			)
			(layer "F.Fab")
		)
		(fp_line
			(start -0.67945 0.3048)
			(end -0.67945 -0.305054)
			(stroke
				(width 0.1)
				(type default)
			)
			(layer "F.Fab")
		)
		(fp_line
			(start -0.67945 -0.305054)
			(end -0.12065 -0.305054)
			(stroke
				(width 0.1)
				(type default)
			)
			(layer "F.Fab")
		)
		(pad "1" smd circle
			(at -0.40005 0 180)
			(size 0 0)
			(layers "F.Cu" "F.Mask" "F.Paste")
			(net "SWB_HSC_EN")
		)
		(pad "2" smd circle
			(at 0.40005 0 180)
			(size 0 0)
			(layers "F.Cu" "F.Mask" "F.Paste")
			(net "SWB_HSC_EN_R")
		)
	)
)
